Created on Valor NPI 9.6 Update 2 - Netlist Compare Summary.
DATE :  14 Oct 2016
TIME :  10:10:53


     MISMATCH SUMMARY REPORT
     -----------------------

Job  : 15968-1a_200403100      Job  : 15968-1a_200403100
Step : db                      Step : db
Type : CAD                     Type : CURCAD

-----------------------------------------------

 Mismatch Type: shorted

   GND                   -   NET00001            
   AGND_P3V3             -    "                  

 Total : 1
-----------------------------------------------

 Mismatch Type: broken


 Total : 0
-----------------------------------------------

 Mismatch Type: missing


 Total : 0
-----------------------------------------------

 Mismatch Type: extra


 Total : 0
-----------------------------------------------
